FILE_TYPE = MACRO_DRAWING;
SET COLOR_WIRE YELLOW;
SET COLOR_PROP ORANGE;
SET COLOR_DOT WHITE;
SET COLOR_ARC YELLOW;
SET COLOR_BODY GREEN;
SET COLOR_NOTE PURPLE;
SET PROP_DISPLAY VALUE;
SET PAGE_NUMBER P130;
FORCEADD NC7SB3157P6X..1
R 2
(-4900 5025);
FORCEPROP 1 LAST LOCATION U8000
J 2
(-4756 5406);
DISPLAY 0.723404 (-4756 5406);
PAINT GREEN (-4756 5406);
FORCEPROP 2 LAST SEC 1
J 0
(-4775 5550);
DISPLAY 0.680851 (-4775 5550);
PAINT MONO (-4775 5550);
DISPLAY INVISIBLE (-4775 5550);
FORCEPROP 2 LASTPIN (-5200 4975) $PN 4
J 2
(-5210 4985);
DISPLAY 0.680851 (-5210 4985);
PAINT MONO (-5210 4985);
FORCEPROP 2 LASTPIN (-4600 4975) $PN 3
J 0
(-4590 4985);
DISPLAY 0.680851 (-4590 4985);
PAINT MONO (-4590 4985);
FORCEPROP 2 LASTPIN (-4600 5075) $PN 1
J 0
(-4590 5085);
DISPLAY 0.680851 (-4590 5085);
PAINT MONO (-4590 5085);
FORCEPROP 2 LASTPIN (-4600 5025) $PN 2
J 0
(-4590 5035);
DISPLAY 0.680851 (-4590 5035);
PAINT MONO (-4590 5035);
FORCEPROP 2 LASTPIN (-5200 5075) $PN 6
J 2
(-5210 5085);
DISPLAY 0.680851 (-5210 5085);
PAINT MONO (-5210 5085);
FORCEPROP 2 LASTPIN (-5200 5025) $PN 5
J 2
(-5210 5035);
DISPLAY 0.680851 (-5210 5035);
PAINT MONO (-5210 5035);
FORCEPROP 2 LAST VALUE NC7SB3157P6X
J 2
(-4775 5450);
DISPLAY 0.680851 (-4775 5450);
FORCEPROP 2 LAST PART_TYPE SMLF
J 2
(-4775 5500);
DISPLAY 0.680851 (-4775 5500);
FORCEPROP 1 LAST MATERIAL IC
J 2
(-4756 5132);
DISPLAY 0.723404 (-4756 5132);
PAINT GREEN (-4756 5132);
FORCEPROP 2 LAST SEC_TYPE 
J 0
(-4775 5550);
DISPLAY 0.680851 (-4775 5550);
DISPLAY INVISIBLE (-4775 5550);
FORCEPROP 1 LAST CDS_LMAN_SYM_OUTLINE -150,100,150,-100
J 2
(-4900 5025);
DISPLAY 0.468085 (-4900 5025);
PAINT GREEN (-4900 5025);
DISPLAY INVISIBLE (-4900 5025);
FORCEPROP 1 LAST NEEDS_NO_SIZE TRUE
J 2
(-4900 5025);
DISPLAY 0.723404 (-4900 5025);
PAINT GREEN (-4900 5025);
DISPLAY INVISIBLE (-4900 5025);
FORCEPROP 2 LAST CDS_LIB pure_quanta
J 2
(-4900 5025);
DISPLAY INVISIBLE (-4900 5025);
FORCEPROP 1 LAST PATH I1
J 2
(-4900 5025);
DISPLAY 0.723404 (-4900 5025);
PAINT GREEN (-4900 5025);
DISPLAY INVISIBLE (-4900 5025);
FORCEPROP 1 LAST PART_NUMBER ALSB3157000
J 2
(-4756 5259);
DISPLAY 0.723404 (-4756 5259);
PAINT GREEN (-4756 5259);
DISPLAY INVISIBLE (-4756 5259);
FORCEADD OFFPAGE..2
(-3425 4975);
FORCEPROP 2 LAST $XR1 153 
J 0
(-3146 4975);
DISPLAY 0.638298 (-3146 4975);
PAINT MONO (-3146 4975);
FORCEPROP 2 LAST $XR0 81 
J 0
(-3236 4975);
DISPLAY 0.638298 (-3236 4975);
PAINT MONO (-3236 4975);
FORCEPROP 2 LAST CDS_LIB standard
J 0
(-3425 4975);
DISPLAY INVISIBLE (-3425 4975);
FORCEPROP 1 LAST OFFPAGE TRUE
J 0
(-3100 4850);
DISPLAY 0.872340 (-3100 4850);
DISPLAY INVISIBLE (-3100 4850);
FORCEPROP 1 LAST COMMENT_BODY TRUE
J 0
(-3470 4880);
DISPLAY 0.872340 (-3470 4880);
PAINT GREEN (-3470 4880);
DISPLAY INVISIBLE (-3470 4880);
FORCEPROP 2 LAST PATH I10
J 0
(-3250 5050);
DISPLAY 0.680851 (-3250 5050);
DISPLAY INVISIBLE (-3250 5050);
FORCEADD Q_RES..2
(-2750 6050);
FORCEPROP 1 LAST LOCATION R8035
J 0
(-2705 6175);
DISPLAY 0.978723 (-2705 6175);
FORCEPROP 0 LAST $SEC 1
J 0
(-2700 6225);
DISPLAY 0.680851 (-2700 6225);
PAINT MONO (-2700 6225);
DISPLAY INVISIBLE (-2700 6225);
FORCEPROP 0 LAST CDS_SEC 1
J 0
(-2700 6225);
DISPLAY 0.680851 (-2700 6225);
DISPLAY INVISIBLE (-2700 6225);
FORCEPROP 1 LASTPIN (-2750 6150) $PN 1
J 0
(-2745 6112);
DISPLAY 0.787234 (-2745 6112);
PAINT MONO (-2745 6112);
FORCEPROP 1 LASTPIN (-2750 5950) $PN 2
J 0
(-2745 5960);
DISPLAY 0.787234 (-2745 5960);
PAINT MONO (-2745 5960);
FORCEPROP 1 LAST TOLERANCE 5%
J 0
(-2705 6075);
DISPLAY 0.978723 (-2705 6075);
FORCEPROP 1 LAST VALUE 4.7K
J 0
(-2705 6125);
DISPLAY 0.978723 (-2705 6125);
FORCEPROP 1 LAST WATTAGE 1/16W
J 0
(-2710 6025);
DISPLAY 0.978723 (-2710 6025);
FORCEPROP 1 LAST MATERIAL EMPTY
J 0
(-2710 5975);
DISPLAY 0.978723 (-2710 5975);
FORCEPROP 1 LAST PACK_TYPE 0402LF
J 0
(-2725 5925);
DISPLAY 0.978723 (-2725 5925);
FORCEPROP 2 LAST CDS_LIB pure_quanta
J 0
(-2750 6050);
DISPLAY INVISIBLE (-2750 6050);
FORCEPROP 1 LAST PATH I11
J 0
(-2700 6225);
DISPLAY 0.978723 (-2700 6225);
PAINT WHITE (-2700 6225);
DISPLAY INVISIBLE (-2700 6225);
FORCEPROP 1 LAST PART_NUMBER CS24702JB10
J 0
(-2710 5925);
DISPLAY 0.978723 (-2710 5925);
DISPLAY INVISIBLE (-2710 5925);
FORCEADD Q_RES..2
(-2350 6050);
FORCEPROP 1 LAST LOCATION R8036
J 0
(-2305 6175);
DISPLAY 0.978723 (-2305 6175);
FORCEPROP 0 LAST $SEC 1
J 0
(-2300 6225);
DISPLAY 0.680851 (-2300 6225);
PAINT MONO (-2300 6225);
DISPLAY INVISIBLE (-2300 6225);
FORCEPROP 0 LAST CDS_SEC 1
J 0
(-2300 6225);
DISPLAY 0.680851 (-2300 6225);
DISPLAY INVISIBLE (-2300 6225);
FORCEPROP 1 LASTPIN (-2350 6150) $PN 1
J 0
(-2345 6112);
DISPLAY 0.787234 (-2345 6112);
PAINT MONO (-2345 6112);
FORCEPROP 1 LASTPIN (-2350 5950) $PN 2
J 0
(-2345 5960);
DISPLAY 0.787234 (-2345 5960);
PAINT MONO (-2345 5960);
FORCEPROP 1 LAST VALUE 4.7K
J 0
(-2305 6125);
DISPLAY 0.978723 (-2305 6125);
FORCEPROP 1 LAST WATTAGE 1/16W
J 0
(-2310 6025);
DISPLAY 0.978723 (-2310 6025);
FORCEPROP 1 LAST TOLERANCE 5%
J 0
(-2305 6075);
DISPLAY 0.978723 (-2305 6075);
FORCEPROP 1 LAST MATERIAL EMPTY
J 0
(-2310 5975);
DISPLAY 0.978723 (-2310 5975);
FORCEPROP 1 LAST PACK_TYPE 0402LF
J 0
(-2300 5925);
DISPLAY 0.978723 (-2300 5925);
FORCEPROP 2 LAST CDS_LIB pure_quanta
J 0
(-2350 6050);
DISPLAY INVISIBLE (-2350 6050);
FORCEPROP 1 LAST PATH I12
J 0
(-2300 6225);
DISPLAY 0.978723 (-2300 6225);
PAINT WHITE (-2300 6225);
DISPLAY INVISIBLE (-2300 6225);
FORCEPROP 1 LAST PART_NUMBER CS24702JB10
J 0
(-2310 5925);
DISPLAY 0.978723 (-2310 5925);
DISPLAY INVISIBLE (-2310 5925);
FORCEADD OFFPAGE..1
(-3550 5850);
FORCEPROP 2 LASTPIN (-3500 5850) SIG_NAME ESPI_CPU0_ALERT_N
J 0
(-3485 5860);
DISPLAY 0.680851 (-3485 5860);
FORCEPROP 2 LAST $XR1 150 
J 0
(-3952 5850);
DISPLAY 0.638298 (-3952 5850);
PAINT MONO (-3952 5850);
FORCEPROP 2 LAST $XR0 153 
J 0
(-3832 5850);
DISPLAY 0.638298 (-3832 5850);
PAINT MONO (-3832 5850);
FORCEPROP 2 LAST CDS_LIB standard
J 0
(-3550 5850);
DISPLAY INVISIBLE (-3550 5850);
FORCEPROP 1 LAST OFFPAGE TRUE
J 0
(-3225 5725);
DISPLAY 0.872340 (-3225 5725);
PAINT GREEN (-3225 5725);
DISPLAY INVISIBLE (-3225 5725);
FORCEPROP 1 LAST COMMENT_BODY TRUE
J 0
(-3425 5750);
DISPLAY 0.872340 (-3425 5750);
PAINT PEACH (-3425 5750);
DISPLAY INVISIBLE (-3425 5750);
FORCEPROP 2 LAST PATH I13
J 0
(-3500 5925);
DISPLAY 0.680851 (-3500 5925);
DISPLAY INVISIBLE (-3500 5925);
FORCEADD OFFPAGE..1
(-3550 5700);
FORCEPROP 2 LAST $XR1 81 
J 0
(-3922 5700);
DISPLAY 0.638298 (-3922 5700);
PAINT MONO (-3922 5700);
FORCEPROP 2 LAST $XR0 153 
J 0
(-3832 5700);
DISPLAY 0.638298 (-3832 5700);
PAINT MONO (-3832 5700);
FORCEPROP 2 LAST CDS_LIB standard
J 0
(-3550 5700);
DISPLAY INVISIBLE (-3550 5700);
FORCEPROP 1 LAST OFFPAGE TRUE
J 0
(-3225 5575);
DISPLAY 0.872340 (-3225 5575);
PAINT GREEN (-3225 5575);
DISPLAY INVISIBLE (-3225 5575);
FORCEPROP 1 LAST COMMENT_BODY TRUE
J 0
(-3425 5600);
DISPLAY 0.872340 (-3425 5600);
PAINT PEACH (-3425 5600);
DISPLAY INVISIBLE (-3425 5600);
FORCEPROP 2 LAST PATH I14
J 0
(-3500 5775);
DISPLAY 0.680851 (-3500 5775);
DISPLAY INVISIBLE (-3500 5775);
FORCEADD UNIVERSAL_POWER..1
(-2350 6375);
FORCEPROP 3 LASTPIN (-2350 6325) SIG_NAME PVDD18_S5_P0\g
J 0
(-2340 6335);
DISPLAY 0.659574 (-2340 6335);
PAINT MONO (-2340 6335);
DISPLAY INVISIBLE (-2340 6335);
FORCEPROP 1 LAST HDL_POWER PVDD18_S5_P0
J 1
(-2350 6425);
DISPLAY 0.489362 (-2350 6425);
PAINT GREEN (-2350 6425);
FORCEPROP 2 LAST CDS_LIB pure_quanta_power
J 0
(-2350 6375);
DISPLAY INVISIBLE (-2350 6375);
FORCEPROP 1 LAST PATH I16
J 0
(-2300 6400);
DISPLAY 0.872340 (-2300 6400);
PAINT AQUA (-2300 6400);
DISPLAY INVISIBLE (-2300 6400);
FORCEADD UNIVERSAL_POWER..1
(-2750 6375);
FORCEPROP 3 LASTPIN (-2750 6325) SIG_NAME P1V8_AUX\g
J 0
(-2740 6335);
DISPLAY 0.659574 (-2740 6335);
PAINT MONO (-2740 6335);
DISPLAY INVISIBLE (-2740 6335);
FORCEPROP 1 LAST HDL_POWER P1V8_AUX
J 1
(-2750 6425);
DISPLAY 0.617021 (-2750 6425);
PAINT GREEN (-2750 6425);
FORCEPROP 2 LAST CDS_LIB pure_quanta_power
J 0
(-2750 6375);
DISPLAY INVISIBLE (-2750 6375);
FORCEPROP 1 LAST PATH I17
J 0
(-2700 6400);
DISPLAY 0.872340 (-2700 6400);
PAINT AQUA (-2700 6400);
DISPLAY INVISIBLE (-2700 6400);
FORCEADD GND..1
R 1
(-4325 5025);
FORCEPROP 3 LASTPIN (-4375 5025) SIG_NAME GND\g
J 0
(-4365 5035);
DISPLAY 0.659574 (-4365 5035);
PAINT MONO (-4365 5035);
DISPLAY INVISIBLE (-4365 5035);
FORCEPROP 1 LAST SIZE 1B
R 1
J 0
(-4275 5100);
DISPLAY 0.872340 (-4275 5100);
PAINT GREEN (-4275 5100);
DISPLAY INVISIBLE (-4275 5100);
FORCEPROP 2 LAST CDS_LIB pure_quanta_power
R 1
J 0
(-4325 5025);
DISPLAY INVISIBLE (-4325 5025);
FORCEPROP 1 LAST HDL_POWER GND
R 1
J 0
(-4475 5025);
DISPLAY 0.872340 (-4475 5025);
PAINT GREEN (-4475 5025);
DISPLAY INVISIBLE (-4475 5025);
FORCEPROP 1 LAST PATH I2
R 1
J 0
(-4325 5100);
DISPLAY 0.872340 (-4325 5100);
PAINT AQUA (-4325 5100);
DISPLAY INVISIBLE (-4325 5100);
FORCEADD OFFPAGE..2
(-2600 5075);
FORCEPROP 2 LAST $XR1 153 
J 0
(-2291 5075);
DISPLAY 0.638298 (-2291 5075);
PAINT MONO (-2291 5075);
FORCEPROP 2 LAST $XR0 150 
J 0
(-2411 5075);
DISPLAY 0.638298 (-2411 5075);
PAINT MONO (-2411 5075);
FORCEPROP 2 LAST CDS_LIB standard
J 0
(-2600 5075);
DISPLAY INVISIBLE (-2600 5075);
FORCEPROP 1 LAST OFFPAGE TRUE
J 0
(-2275 4950);
DISPLAY 0.872340 (-2275 4950);
DISPLAY INVISIBLE (-2275 4950);
FORCEPROP 1 LAST COMMENT_BODY TRUE
J 0
(-2645 4980);
DISPLAY 0.872340 (-2645 4980);
PAINT GREEN (-2645 4980);
DISPLAY INVISIBLE (-2645 4980);
FORCEPROP 2 LAST PATH I21
J 0
(-2400 5125);
DISPLAY 0.680851 (-2400 5125);
DISPLAY INVISIBLE (-2400 5125);
FORCEADD OFFPAGE..1
(-6375 4975);
FORCEPROP 2 LAST $XR0 29 
J 0
(-6596 4975);
DISPLAY 0.638298 (-6596 4975);
PAINT MONO (-6596 4975);
FORCEPROP 2 LAST CDS_LIB standard
J 0
(-6375 4975);
DISPLAY INVISIBLE (-6375 4975);
FORCEPROP 1 LAST OFFPAGE TRUE
J 0
(-6050 4850);
DISPLAY 0.872340 (-6050 4850);
PAINT GREEN (-6050 4850);
DISPLAY INVISIBLE (-6050 4850);
FORCEPROP 1 LAST COMMENT_BODY TRUE
J 0
(-6250 4875);
DISPLAY 0.872340 (-6250 4875);
PAINT PEACH (-6250 4875);
DISPLAY INVISIBLE (-6250 4875);
FORCEPROP 2 LAST PATH I22
J 0
(-6625 5025);
DISPLAY 0.680851 (-6625 5025);
DISPLAY INVISIBLE (-6625 5025);
FORCEADD Q_RES..1
(-3475 5075);
FORCEPROP 1 LAST LOCATION R8034
J 0
(-3700 5075);
DISPLAY 0.638298 (-3700 5075);
FORCEPROP 2 LAST SEC 1
J 0
(-3525 5275);
DISPLAY 0.680851 (-3525 5275);
PAINT MONO (-3525 5275);
DISPLAY INVISIBLE (-3525 5275);
FORCEPROP 1 LASTPIN (-3575 5075) $PN 1
J 0
(-3563 5087);
DISPLAY 0.787234 (-3563 5087);
PAINT MONO (-3563 5087);
FORCEPROP 1 LASTPIN (-3375 5075) $PN 2
J 0
(-3413 5087);
DISPLAY 0.787234 (-3413 5087);
PAINT MONO (-3413 5087);
FORCEPROP 1 LAST WATTAGE 1/16W
J 2
(-3500 5250);
DISPLAY 0.638298 (-3500 5250);
FORCEPROP 1 LAST MATERIAL CHIP
J 0
(-3525 5125);
DISPLAY 0.638298 (-3525 5125);
FORCEPROP 1 LAST VALUE 0
J 2
(-3550 5150);
DISPLAY 0.638298 (-3550 5150);
FORCEPROP 1 LAST PACK_TYPE 0402LF
J 0
(-3475 5250);
DISPLAY 0.638298 (-3475 5250);
FORCEPROP 1 LAST TOLERANCE 5%
J 0
(-3400 5150);
DISPLAY 0.638298 (-3400 5150);
FORCEPROP 2 LAST SEC_TYPE 0402LF
J 0
(-3525 5275);
DISPLAY 0.680851 (-3525 5275);
DISPLAY INVISIBLE (-3525 5275);
FORCEPROP 2 LAST CDS_LIB pure_quanta
J 0
(-3475 5075);
DISPLAY INVISIBLE (-3475 5075);
FORCEPROP 1 LAST PATH I23
J 0
(-3525 5225);
DISPLAY 0.978723 (-3525 5225);
PAINT WHITE (-3525 5225);
DISPLAY INVISIBLE (-3525 5225);
FORCEPROP 1 LAST PART_NUMBER CS00002JB13
J 0
(-3650 5200);
DISPLAY 0.638298 (-3650 5200);
DISPLAY INVISIBLE (-3650 5200);
FORCEADD Q_RES..1
(-4950 4650);
FORCEPROP 1 LAST LOCATION R1197
J 0
(-5175 4650);
DISPLAY 0.808511 (-5175 4650);
FORCEPROP 0 LAST $SEC 1
J 0
(-5175 4700);
DISPLAY 0.680851 (-5175 4700);
PAINT MONO (-5175 4700);
DISPLAY INVISIBLE (-5175 4700);
FORCEPROP 0 LAST CDS_SEC 1
J 0
(-5175 4700);
DISPLAY 0.680851 (-5175 4700);
DISPLAY INVISIBLE (-5175 4700);
FORCEPROP 1 LASTPIN (-5050 4650) $PN 1
J 0
(-5038 4662);
DISPLAY 0.787234 (-5038 4662);
PAINT MONO (-5038 4662);
FORCEPROP 1 LASTPIN (-4850 4650) $PN 2
J 0
(-4888 4662);
DISPLAY 0.787234 (-4888 4662);
PAINT MONO (-4888 4662);
FORCEPROP 1 LAST WATTAGE 1/16W
J 2
(-5100 4525);
DISPLAY 0.808511 (-5100 4525);
FORCEPROP 1 LAST MATERIAL EMPTY
J 0
(-5075 4525);
DISPLAY 0.808511 (-5075 4525);
FORCEPROP 1 LAST TOLERANCE 5%
J 0
(-5075 4575);
DISPLAY 0.808511 (-5075 4575);
FORCEPROP 1 LAST VALUE 0
J 2
(-5100 4575);
DISPLAY 0.808511 (-5100 4575);
FORCEPROP 1 LAST PACK_TYPE 0402LF
J 0
(-4875 4525);
DISPLAY 0.808511 (-4875 4525);
FORCEPROP 2 LAST CDS_LIB pure_quanta
J 0
(-4950 4650);
DISPLAY INVISIBLE (-4950 4650);
FORCEPROP 1 LAST PATH I24
J 0
(-5000 4800);
DISPLAY 0.978723 (-5000 4800);
PAINT WHITE (-5000 4800);
DISPLAY INVISIBLE (-5000 4800);
FORCEPROP 1 LAST PART_NUMBER CS00002JB13
J 0
(-5000 4575);
DISPLAY 0.808511 (-5000 4575);
DISPLAY INVISIBLE (-5000 4575);
FORCEADD UNIVERSAL_POWER..1
(-7325 5850);
FORCEPROP 3 LASTPIN (-7325 5800) SIG_NAME P1V8_AUX\g
J 0
(-7315 5810);
DISPLAY 0.659574 (-7315 5810);
PAINT MONO (-7315 5810);
DISPLAY INVISIBLE (-7315 5810);
FORCEPROP 1 LAST HDL_POWER P1V8_AUX
J 1
(-7325 5900);
DISPLAY 0.617021 (-7325 5900);
PAINT GREEN (-7325 5900);
FORCEPROP 2 LAST CDS_LIB pure_quanta_power
J 0
(-7325 5850);
DISPLAY INVISIBLE (-7325 5850);
FORCEPROP 1 LAST PATH I3
J 0
(-7275 5875);
DISPLAY 0.872340 (-7275 5875);
PAINT AQUA (-7275 5875);
DISPLAY INVISIBLE (-7275 5875);
FORCEADD Q_CAP..1
R 2
(-7325 5500);
FORCEPROP 1 LAST LOCATION C8007
J 2
(-7375 5600);
DISPLAY 0.978723 (-7375 5600);
FORCEPROP 0 LAST $SEC 1
J 0
(-7375 5650);
DISPLAY 0.680851 (-7375 5650);
PAINT MONO (-7375 5650);
DISPLAY INVISIBLE (-7375 5650);
FORCEPROP 0 LAST CDS_SEC 1
J 0
(-7375 5650);
DISPLAY 0.680851 (-7375 5650);
DISPLAY INVISIBLE (-7375 5650);
FORCEPROP 1 LASTPIN (-7325 5600) $PN 1
J 2
(-7335 5580);
DISPLAY 0.787234 (-7335 5580);
PAINT MONO (-7335 5580);
FORCEPROP 1 LASTPIN (-7325 5400) $PN 2
J 2
(-7335 5380);
DISPLAY 0.787234 (-7335 5380);
PAINT MONO (-7335 5380);
FORCEPROP 1 LAST MATERIAL X7R
J 2
(-7375 5400);
DISPLAY 0.978723 (-7375 5400);
FORCEPROP 1 LAST PACK_TYPE 0402
J 2
(-7375 5300);
DISPLAY 0.978723 (-7375 5300);
FORCEPROP 1 LAST TOLERANCE 10%
J 2
(-7375 5450);
DISPLAY 0.978723 (-7375 5450);
FORCEPROP 1 LAST VALUE 0.1UF
J 2
(-7375 5550);
DISPLAY 0.978723 (-7375 5550);
FORCEPROP 1 LAST VOLTAGE 25V
J 2
(-7375 5500);
DISPLAY 0.978723 (-7375 5500);
FORCEPROP 2 LAST CDS_LIB pure_quanta
J 2
(-7325 5500);
DISPLAY INVISIBLE (-7325 5500);
FORCEPROP 1 LAST PATH I4
J 2
(-7375 5650);
DISPLAY 0.978723 (-7375 5650);
PAINT WHITE (-7375 5650);
DISPLAY INVISIBLE (-7375 5650);
FORCEPROP 1 LAST PART_NUMBER CH4104K1B00
J 2
(-7375 5350);
DISPLAY 0.978723 (-7375 5350);
DISPLAY INVISIBLE (-7375 5350);
FORCEADD GND..1
R 2
(-7325 5250);
FORCEPROP 3 LASTPIN (-7325 5300) SIG_NAME GND\g
J 0
(-7315 5310);
DISPLAY 0.659574 (-7315 5310);
PAINT MONO (-7315 5310);
DISPLAY INVISIBLE (-7315 5310);
FORCEPROP 1 LAST SIZE 1B
J 2
(-7400 5200);
DISPLAY 0.872340 (-7400 5200);
PAINT GREEN (-7400 5200);
DISPLAY INVISIBLE (-7400 5200);
FORCEPROP 2 LAST CDS_LIB pure_quanta_power
R 3
J 0
(-7325 5250);
DISPLAY INVISIBLE (-7325 5250);
FORCEPROP 1 LAST HDL_POWER GND
J 2
(-7325 5400);
DISPLAY 0.872340 (-7325 5400);
PAINT GREEN (-7325 5400);
DISPLAY INVISIBLE (-7325 5400);
FORCEPROP 1 LAST PATH I5
J 2
(-7400 5250);
DISPLAY 0.872340 (-7400 5250);
PAINT AQUA (-7400 5250);
DISPLAY INVISIBLE (-7400 5250);
FORCEADD OFFPAGE..1
(-6400 5075);
FORCEPROP 2 LAST $XR1 83 
J 0
(-6711 5075);
DISPLAY 0.638298 (-6711 5075);
PAINT MONO (-6711 5075);
FORCEPROP 2 LAST $XR0 81 
J 0
(-6621 5075);
DISPLAY 0.638298 (-6621 5075);
PAINT MONO (-6621 5075);
FORCEPROP 2 LAST CDS_LIB standard
J 0
(-6400 5075);
DISPLAY INVISIBLE (-6400 5075);
FORCEPROP 1 LAST OFFPAGE TRUE
J 0
(-6075 4950);
DISPLAY 0.872340 (-6075 4950);
PAINT GREEN (-6075 4950);
DISPLAY INVISIBLE (-6075 4950);
FORCEPROP 1 LAST COMMENT_BODY TRUE
J 0
(-6275 4975);
DISPLAY 0.872340 (-6275 4975);
PAINT PEACH (-6275 4975);
DISPLAY INVISIBLE (-6275 4975);
FORCEPROP 2 LAST PATH I8
J 0
(-6350 5150);
DISPLAY 0.680851 (-6350 5150);
DISPLAY INVISIBLE (-6350 5150);
FORCEADD DNS..2
(-2675 6050);
PAINT RED (-2675 6050);
FORCEPROP 2 LAST CDS_LIB mstr_misc
J 0
(-2675 6050);
DISPLAY INVISIBLE (-2675 6050);
FORCEPROP 1 LAST COMMENT_BODY TRUE
R 1
J 0
(-2600 5825);
DISPLAY 0.872340 (-2600 5825);
PAINT GREEN (-2600 5825);
DISPLAY INVISIBLE (-2600 5825);
FORCEADD DNS..2
(-4900 4650);
PAINT RED (-4900 4650);
FORCEPROP 2 LAST CDS_LIB mstr_misc
J 0
(-4900 4650);
DISPLAY INVISIBLE (-4900 4650);
FORCEPROP 1 LAST COMMENT_BODY TRUE
R 1
J 0
(-4825 4425);
DISPLAY 0.872340 (-4825 4425);
PAINT GREEN (-4825 4425);
DISPLAY INVISIBLE (-4825 4425);
FORCEADD QUANTA_TITLE_BLOCK_C..1
(0 0);
FORCEPROP 0 LAST CDS_CON_LAST_MODIFIED Thu Sep 14 16:12:48 2023
J 0
(-1885 15);
DISPLAY INVISIBLE (-1885 15);
FORCEPROP 1 LAST CUSTOM_TXT_CDS <CON_LAST_MODIFIED>
J 0
(-1885 15);
DISPLAY 0.978723 (-1885 15);
FORCEPROP 2 LAST CUSTOM_TXT_CDS <XR_PAGE_TITLE>
J 0
(-7890 5250);
DISPLAY 0.638298 (-7890 5250);
PAINT PINK (-7890 5250);
DISPLAY INVISIBLE (-7890 5250);
FORCEPROP 1 LAST CUSTOM_TXT_CDS <NAME_2>
J 0
(-3175 50);
FORCEPROP 1 LAST CUSTOM_TXT_CDS <NAME_1>
J 0
(-3175 175);
FORCEPROP 1 LAST CUSTOM_TXT_CDS <Q_NUMBER>
J 0
(-1403 103);
DISPLAY 1.212766 (-1403 103);
FORCEPROP 1 LAST CUSTOM_TXT_CDS <Q_PROJ>
J 0
(-2382 102);
DISPLAY 1.212766 (-2382 102);
FORCEPROP 1 LAST CUSTOM_TXT_CDS <Q_REV>
J 0
(-184 103);
DISPLAY 1.212766 (-184 103);
FORCEPROP 1 LAST CUSTOM_TXT_CDS <CON_PAGE_NUM> OF <CON_TOTAL_PAGES>
J 0
(-446 18);
DISPLAY 0.978723 (-446 18);
FORCEPROP 1 LAST Q_TITLE SCM_SW
J 0
(-9275 50);
DISPLAY 2.446809 (-9275 50);
PAINT GREEN (-9275 50);
FORCEPROP 2 LAST PAGE_BORDER TRUE
J 0
(-7890 5250);
DISPLAY 0.638298 (-7890 5250);
PAINT PINK (-7890 5250);
DISPLAY INVISIBLE (-7890 5250);
FORCEPROP 2 LAST CDS_LIB pure_quanta
J 0
(0 0);
DISPLAY INVISIBLE (0 0);
FORCEPROP 1 LAST CDS_LMAN_SYM_OUTLINE -9475,6775,100,-125
J 0
(0 0);
DISPLAY 0.468085 (0 0);
PAINT GREEN (0 0);
DISPLAY INVISIBLE (0 0);
FORCEPROP 2 LAST CDS_XR_PAGE_TITLE CR-153 : @T6G_MB_LIB.T6G(SCH_1):PAGE153
J 0
(-7890 5250);
DISPLAY 0.638298 (-7890 5250);
PAINT PINK (-7890 5250);
DISPLAY INVISIBLE (-7890 5250);
FORCEPROP 1 LAST Q_DEPT BU9
J 1
(-3763 49);
DISPLAY 1.957447 (-3763 49);
PAINT GREEN (-3763 49);
DISPLAY INVISIBLE (-3763 49);
FORCEPROP 1 LAST COMMENT_BODY TRUE
J 0
(12 -13);
DISPLAY 0.978723 (12 -13);
PAINT GREEN (12 -13);
DISPLAY INVISIBLE (12 -13);
FORCEADD DNS..2
(-2275 6025);
PAINT RED (-2275 6025);
FORCEPROP 2 LAST CDS_LIB mstr_misc
J 0
(-2275 6025);
DISPLAY INVISIBLE (-2275 6025);
FORCEPROP 1 LAST COMMENT_BODY TRUE
R 1
J 0
(-2200 5800);
DISPLAY 0.872340 (-2200 5800);
PAINT GREEN (-2200 5800);
DISPLAY INVISIBLE (-2200 5800);
WIRE 16 -1 (-2350 6150)(-2350 6325);
WIRE 16 -1 (-2750 6150)(-2750 6325);
WIRE 16 -1 (-4600 5025)(-4375 5025);
WIRE 16 -1 (-7325 5400)(-7325 5300);
WIRE 16 -1 (-4850 4650)(-2800 4650);
WIRE 16 -1 (-2800 4650)(-2800 5075);
WIRE 16 -1 (-2800 5075)(-2650 5075);
WIRE 16 -1 (-3375 5075)(-2800 5075);
FORCEPROP 2 LAST SIG_NAME ESPI_CPU0_ALERT_N
J 0
(-3310 5085);
DISPLAY 0.680851 (-3310 5085);
WIRE 16 -1 (-5450 4650)(-5050 4650);
WIRE 16 -1 (-5450 4975)(-5450 4650);
WIRE 16 -1 (-5450 4975)(-5200 4975);
WIRE 16 -1 (-6325 4975)(-5450 4975);
FORCEPROP 2 LAST SIG_NAME ESPI_CPU0_ALERT_P0_N
J 0
(-5935 4985);
DISPLAY 0.680851 (-5935 4985);
WIRE 16 -1 (-5200 5075)(-6350 5075);
FORCEPROP 2 LAST SIG_NAME FM_ESPI_CPU0_ALERT_R_SEL
J 0
(-6185 5085);
DISPLAY 0.680851 (-6185 5085);
WIRE 16 -1 (-4600 4975)(-3475 4975);
FORCEPROP 2 LAST SIG_NAME ESPI_CPU0_ALERT_PLD_N
J 0
(-4185 4985);
DISPLAY 0.702128 (-4185 4985);
WIRE 16 -1 (-6925 5650)(-6925 5025);
WIRE 16 -1 (-7325 5650)(-6925 5650);
WIRE 16 -1 (-6925 5025)(-5200 5025);
WIRE 16 -1 (-7325 5650)(-7325 5800);
WIRE 16 -1 (-7325 5650)(-7325 5600);
WIRE 16 -1 (-3500 5850)(-2750 5850);
WIRE 16 -1 (-2750 5850)(-2750 5950);
WIRE 16 -1 (-2350 5700)(-2350 5950);
WIRE 16 -1 (-3500 5700)(-2350 5700);
FORCEPROP 2 LAST SIG_NAME ESPI_CPU0_ALERT_PLD_N
J 0
(-3485 5710);
DISPLAY 0.680851 (-3485 5710);
WIRE 16 -1 (-3575 5075)(-4600 5075);
FORCEPROP 2 LAST SIG_NAME ESPI_CPU0_ALERT_R1_N
J 0
(-4385 5085);
DISPLAY 0.680851 (-4385 5085);
FORCEPROP 2 LASTPROP $XRERR UNIQUE?
J 0
(-4625 5085);
DISPLAY 0.638298 (-4625 5085);
PAINT MONO (-4625 5085);
DISPLAY INVISIBLE (-4625 5085);
DOT 1 (-7325 5650);
DOT 1 (-5450 4975);
DOT 1 (-2800 5075);
QUIT
